(kicad_pcb
	(version 20221018)
	(generator pcbnew)
	(general
    (thickness 1.656)
  )
	(paper "A4")
	(title_block
    (title "SDI-MIPI Bridge")
    (date "2023-08-09")
    (rev "1.3.4")
    (company "Antmicro")
		(comment 9 "footprints 18-19 of 190")
	)
	(layers
    (0 "F.Cu" signal)
    (1 "In1.Cu" power)
    (2 "In2.Cu" power)
    (3 "In3.Cu" signal)
    (4 "In4.Cu" signal)
    (31 "B.Cu" signal)
    (32 "B.Adhes" user "B.Adhesive")
    (33 "F.Adhes" user "F.Adhesive")
    (34 "B.Paste" user)
    (35 "F.Paste" user)
    (36 "B.SilkS" user "B.Silkscreen")
    (37 "F.SilkS" user "F.Silkscreen")
    (38 "B.Mask" user)
    (39 "F.Mask" user)
    (40 "Dwgs.User" user "User.Drawings")
    (41 "Cmts.User" user "User.Comments")
    (42 "Eco1.User" user "User.Eco1")
    (43 "Eco2.User" user "User.Eco2")
    (44 "Edge.Cuts" user)
    (45 "Margin" user)
    (46 "B.CrtYd" user "B.Courtyard")
    (47 "F.CrtYd" user "F.Courtyard")
    (48 "B.Fab" user)
    (49 "F.Fab" user)
  )
	(footprint "sdi-mipi-bridge-footprints:R_0402_1005Metric" (layer "F.Cu")
    (at 156.945 113.7 180)
    (descr "Resistor SMD 0402")
    (tags "resistor SMD 0402")
    (property "Author" "Antmicro")
    (property "Current" "1A")
    (property "License" "Apache-2.0")
    (property "MPN" "ERJ2GE0R00X")
    (property "Manufacturer" "Panasonic")
    (property "Sheetfile" "sdi-mipi-bridge.kicad_sch")
    (property "Sheetname" "")
    (property "Tolerance" "")
    (property "Val" "0R")
    (property "ki_description" "0R resistor in 0402 package with unspecified tolerance")
    (attr smd)
    (fp_text reference "R37" (at -2.955 -0.4) (layer "F.SilkS")
        (effects (font (size 0.65 0.65) (thickness 0.15)) (justify right bottom))
    )
    (fp_text value "R_0R_0402" (at 0 1.4) (layer "F.Fab") hide
        (effects (font (size 0.7 0.7) (thickness 0.15)) (justify right bottom))
    )
    (fp_text user "Author: Antmicro" (at -0.95 4.169) (layer "F.Fab") hide
        (effects (font (size 0.7 0.7) (thickness 0.15)) (justify right bottom))
    )
    (fp_text user "${REFERENCE}" (at -0.95 3.168) (layer "F.Fab") hide
        (effects (font (size 0.7 0.7) (thickness 0.15)) (justify right bottom))
    )
    (fp_text user "License: Apache-2.0" (at -0.95 5.169) (layer "F.Fab") hide
        (effects (font (size 0.7 0.7) (thickness 0.15)) (justify right bottom))
    )
    (fp_rect (start -0.93 -0.47) (end 0.93 0.47)
      (stroke (width 0.05) (type solid)) (fill none) (layer "F.CrtYd"))
    (fp_rect (start -0.5 -0.25) (end 0.5 0.25)
      (stroke (width 0.15) (type solid)) (fill none) (layer "F.Fab"))
    (pad "1" smd roundrect (at -0.485 0 180) (size 0.59 0.64) (layers "F.Cu" "F.Paste" "F.Mask") (roundrect_rratio 0.25)
      (net 83 "/SDA1") (pintype "passive"))
    (pad "2" smd roundrect (at 0.485 0 180) (size 0.59 0.64) (layers "F.Cu" "F.Paste" "F.Mask") (roundrect_rratio 0.25)
      (net 102 "/SPI_SCK(SDA)") (pintype "passive"))
  )
	(footprint "sdi-mipi-bridge-footprints:R_0402_1005Metric" (layer "F.Cu")
    (at 156.945 108.9 180)
    (descr "Resistor SMD 0402")
    (tags "resistor SMD 0402")
    (property "Author" "Antmicro")
    (property "Current" "1A")
    (property "DNP" "DNP")
    (property "License" "Apache-2.0")
    (property "MPN" "ERJ2GE0R00X")
    (property "Manufacturer" "Panasonic")
    (property "Sheetfile" "sdi-mipi-bridge.kicad_sch")
    (property "Sheetname" "")
    (property "Tolerance" "")
    (property "Val" "0R")
    (property "ki_description" "0R resistor in 0402 package with unspecified tolerance")
    (attr exclude_from_pos_files)
    (fp_text reference "R41" (at -2.955 -0.4) (layer "F.SilkS")
        (effects (font (size 0.65 0.65) (thickness 0.15)) (justify right bottom))
    )
    (fp_text value "R_0R_0402" (at 0 1.4) (layer "F.Fab") hide
        (effects (font (size 0.7 0.7) (thickness 0.15)) (justify right bottom))
    )
    (fp_text user "License: Apache-2.0" (at -0.95 5.169) (layer "F.Fab") hide
        (effects (font (size 0.7 0.7) (thickness 0.15)) (justify right bottom))
    )
    (fp_text user "Author: Antmicro" (at -0.95 4.169) (layer "F.Fab") hide
        (effects (font (size 0.7 0.7) (thickness 0.15)) (justify right bottom))
    )
    (fp_text user "${REFERENCE}" (at -0.95 3.168) (layer "F.Fab") hide
        (effects (font (size 0.7 0.7) (thickness 0.15)) (justify right bottom))
    )
    (fp_rect (start -0.93 -0.47) (end 0.93 0.47)
      (stroke (width 0.05) (type solid)) (fill none) (layer "F.CrtYd"))
    (fp_rect (start -0.5 -0.25) (end 0.5 0.25)
      (stroke (width 0.15) (type solid)) (fill none) (layer "F.Fab"))
    (pad "1" smd roundrect (at -0.485 0 180) (size 0.59 0.64) (layers "F.Cu" "F.Paste" "F.Mask") (roundrect_rratio 0.25)
      (net 81 "/SDA2") (pintype "passive"))
    (pad "2" smd roundrect (at 0.485 0 180) (size 0.59 0.64) (layers "F.Cu" "F.Paste" "F.Mask") (roundrect_rratio 0.25)
      (net 102 "/SPI_SCK(SDA)") (pintype "passive"))
  )
)
